# T6G (Grand Teton) — schematic netlist excerpt (pin names and nets, part order shuffled) for the footprints in the layout excerpt that follows; sources: Cadence DE-HDL packaged netlist, KiCad conversion of 04192023_DAF0TMB3IC0_F0TG_MB_C_brd_V02_OCP.brd

PR2527  Q_RES  10 1% CHIP  pkg 0402LF  page 266 : A = P12V_HSC_SENSE2_N ; B = P12V_HSC_SENSE2_R4_N
C638  Q_CAP  4.7UF 6.3V 20% X6S  pkg 0402  page 290 : A = P0V9_CPU0_RT1_2A ; B = GND

(kicad_pcb
	(version 20260206)
	(generator "pcbnew")
	(generator_version "10.0")
	(general
		(thickness 1.6)
		(legacy_teardrops no)
	)
	(paper "A4")
	(title_block
		(title "04192023_DAF0TMB3IC0_F0TG_MB_C_brd_V02_OCP.brd")
		(comment 1 "Grand Teton / footprints 6081-6082 of 8354")
	)
	(layers
		(0 "F.Cu" signal "TOP")
		(4 "In1.Cu" signal "GND")
		(6 "In2.Cu" signal "IN1")
		(8 "In3.Cu" signal "GND1")
		(10 "In4.Cu" signal "IN2")
		(12 "In5.Cu" signal "GND2")
		(14 "In6.Cu" signal "IN3")
		(16 "In7.Cu" signal "GND3")
		(18 "In8.Cu" signal "VCC")
		(20 "In9.Cu" signal "VCC1")
		(22 "In10.Cu" signal "GND4")
		(24 "In11.Cu" signal "IN4")
		(26 "In12.Cu" signal "GND5")
		(28 "In13.Cu" signal "IN5")
		(30 "In14.Cu" signal "GND6")
		(32 "In15.Cu" signal "IN6")
		(34 "In16.Cu" signal "GND7")
		(2 "B.Cu" signal "BOTTOM")
		(9 "F.Adhes" user "F.Adhesive")
		(11 "B.Adhes" user "B.Adhesive")
		(13 "F.Paste" user "Package Geometry/Pastemask Top")
		(15 "B.Paste" user "Package Geometry/Pastemask Bottom")
		(5 "F.SilkS" user "Ref Des/Silkscreen Top")
		(7 "B.SilkS" user "Ref Des/Silkscreen Bottom")
		(1 "F.Mask" user "Board Geometry/Soldermask Top")
		(3 "B.Mask" user "Board Geometry/Soldermask Bottom")
		(17 "Dwgs.User" user "User.Drawings")
		(19 "Cmts.User" user "User.Comments")
		(21 "Eco1.User" user "User.Eco1")
		(23 "Eco2.User" user "User.Eco2")
		(25 "Edge.Cuts" user "Board Geometry/Outline")
		(27 "Margin" user)
		(31 "F.CrtYd" user "Package Geometry/Place Bound Top")
		(29 "B.CrtYd" user "Package Geometry/Place Bound Bottom")
		(35 "F.Fab" user "Ref Des/Assembly Top")
		(33 "B.Fab" user "Ref Des/Assembly Bottom")
	)
	(footprint ""
		(layer "B.Cu")
		(at 206.429356 -383.612136 180)
		(property "Reference" "PR2527"
			(at 0 0 0)
			(layer "B.SilkS")
			(hide yes)
			(effects
				(font
					(size 1.27 1.27)
				)
				(justify mirror)
			)
		)
		(property "Value" ""
			(at 0 0 0)
			(layer "B.Fab")
			(effects
				(font
					(size 1.27 1.27)
				)
				(justify mirror)
			)
		)
		(duplicate_pad_numbers_are_jumpers no)
		(fp_line
			(start 0.7874 0.4064)
			(end 0.7874 -0.4064)
			(stroke
				(width 0.1524)
				(type default)
			)
			(layer "B.SilkS")
		)
		(fp_line
			(start 0.7874 -0.4064)
			(end -0.7874 -0.4064)
			(stroke
				(width 0.1524)
				(type default)
			)
			(layer "B.SilkS")
		)
		(fp_line
			(start -0.7874 0.4064)
			(end 0.7874 0.4064)
			(stroke
				(width 0.1524)
				(type default)
			)
			(layer "B.SilkS")
		)
		(fp_line
			(start -0.7874 -0.4064)
			(end -0.7874 0.4064)
			(stroke
				(width 0.1524)
				(type default)
			)
			(layer "B.SilkS")
		)
		(fp_line
			(start 0.67945 0.3048)
			(end 0.67945 -0.305054)
			(stroke
				(width 0.1)
				(type default)
			)
			(layer "B.Fab")
		)
		(fp_line
			(start 0.67945 -0.305054)
			(end 0.12065 -0.305054)
			(stroke
				(width 0.1)
				(type default)
			)
			(layer "B.Fab")
		)
		(fp_line
			(start 0.12065 0.3048)
			(end 0.67945 0.3048)
			(stroke
				(width 0.1)
				(type default)
			)
			(layer "B.Fab")
		)
		(fp_line
			(start 0.12065 0.2794)
			(end 0.12065 0.3048)
			(stroke
				(width 0.1)
				(type default)
			)
			(layer "B.Fab")
		)
		(fp_line
			(start 0.12065 -0.2794)
			(end -0.12065 -0.2794)
			(stroke
				(width 0.1)
				(type default)
			)
			(layer "B.Fab")
		)
		(fp_line
			(start 0.12065 -0.305054)
			(end 0.12065 -0.2794)
			(stroke
				(width 0.1)
				(type default)
			)
			(layer "B.Fab")
		)
		(fp_line
			(start -0.120396 0.3048)
			(end -0.120396 0.2794)
			(stroke
				(width 0.1)
				(type default)
			)
			(layer "B.Fab")
		)
		(fp_line
			(start -0.120396 0.2794)
			(end 0.12065 0.2794)
			(stroke
				(width 0.1)
				(type default)
			)
			(layer "B.Fab")
		)
		(fp_line
			(start -0.12065 -0.2794)
			(end -0.12065 -0.3048)
			(stroke
				(width 0.1)
				(type default)
			)
			(layer "B.Fab")
		)
		(fp_line
			(start -0.12065 -0.3048)
			(end -0.67945 -0.3048)
			(stroke
				(width 0.1)
				(type default)
			)
			(layer "B.Fab")
		)
		(fp_line
			(start -0.67945 0.3048)
			(end -0.120396 0.3048)
			(stroke
				(width 0.1)
				(type default)
			)
			(layer "B.Fab")
		)
		(fp_line
			(start -0.67945 -0.3048)
			(end -0.67945 0.3048)
			(stroke
				(width 0.1)
				(type default)
			)
			(layer "B.Fab")
		)
		(pad "1" smd circle
			(at 0.40005 0)
			(size 0 0)
			(layers "B.Cu" "B.Mask" "B.Paste")
			(net "P12V_HSC_SENSE2_N")
		)
		(pad "2" smd circle
			(at -0.40005 0)
			(size 0 0)
			(layers "B.Cu" "B.Mask" "B.Paste")
			(net "P12V_HSC_SENSE2_R4_N")
		)
	)
	(footprint ""
		(layer "B.Cu")
		(at 338.318856 -398.942052 90)
		(property "Reference" "C638"
			(at 0 0 90)
			(layer "B.SilkS")
			(hide yes)
			(effects
				(font
					(size 1.27 1.27)
				)
				(justify mirror)
			)
		)
		(property "Value" ""
			(at 0 0 90)
			(layer "B.Fab")
			(effects
				(font
					(size 1.27 1.27)
				)
				(justify mirror)
			)
		)
		(duplicate_pad_numbers_are_jumpers no)
		(fp_line
			(start 0.7874 -0.4064)
			(end -0.7874 -0.4064)
			(stroke
				(width 0.1524)
				(type default)
			)
			(layer "B.SilkS")
		)
		(fp_line
			(start -0.7874 -0.4064)
			(end -0.7874 0.4064)
			(stroke
				(width 0.1524)
				(type default)
			)
			(layer "B.SilkS")
		)
		(fp_line
			(start 0.7874 0.4064)
			(end 0.7874 -0.4064)
			(stroke
				(width 0.1524)
				(type default)
			)
			(layer "B.SilkS")
		)
		(fp_line
			(start -0.7874 0.4064)
			(end 0.7874 0.4064)
			(stroke
				(width 0.1524)
				(type default)
			)
			(layer "B.SilkS")
		)
		(fp_line
			(start 0.67945 -0.305054)
			(end 0.12065 -0.305054)
			(stroke
				(width 0.1)
				(type default)
			)
			(layer "B.Fab")
		)
		(fp_line
			(start 0.12065 -0.305054)
			(end 0.12065 -0.2794)
			(stroke
				(width 0.1)
				(type default)
			)
			(layer "B.Fab")
		)
		(fp_line
			(start -0.12065 -0.3048)
			(end -0.67945 -0.3048)
			(stroke
				(width 0.1)
				(type default)
			)
			(layer "B.Fab")
		)
		(fp_line
			(start -0.67945 -0.3048)
			(end -0.67945 0.3048)
			(stroke
				(width 0.1)
				(type default)
			)
			(layer "B.Fab")
		)
		(fp_line
			(start 0.12065 -0.2794)
			(end -0.12065 -0.2794)
			(stroke
				(width 0.1)
				(type default)
			)
			(layer "B.Fab")
		)
		(fp_line
			(start -0.12065 -0.2794)
			(end -0.12065 -0.3048)
			(stroke
				(width 0.1)
				(type default)
			)
			(layer "B.Fab")
		)
		(fp_line
			(start 0.12065 0.2794)
			(end 0.12065 0.3048)
			(stroke
				(width 0.1)
				(type default)
			)
			(layer "B.Fab")
		)
		(fp_line
			(start -0.120396 0.2794)
			(end 0.12065 0.2794)
			(stroke
				(width 0.1)
				(type default)
			)
			(layer "B.Fab")
		)
		(fp_line
			(start 0.67945 0.3048)
			(end 0.67945 -0.305054)
			(stroke
				(width 0.1)
				(type default)
			)
			(layer "B.Fab")
		)
		(fp_line
			(start 0.12065 0.3048)
			(end 0.67945 0.3048)
			(stroke
				(width 0.1)
				(type default)
			)
			(layer "B.Fab")
		)
		(fp_line
			(start -0.120396 0.3048)
			(end -0.120396 0.2794)
			(stroke
				(width 0.1)
				(type default)
			)
			(layer "B.Fab")
		)
		(fp_line
			(start -0.67945 0.3048)
			(end -0.120396 0.3048)
			(stroke
				(width 0.1)
				(type default)
			)
			(layer "B.Fab")
		)
		(pad "1" smd circle
			(at 0.40005 0 270)
			(size 0 0)
			(layers "B.Cu" "B.Mask" "B.Paste")
			(net "P0V9_CPU0_RT1_2A")
		)
		(pad "2" smd circle
			(at -0.40005 0 270)
			(size 0 0)
			(layers "B.Cu" "B.Mask" "B.Paste")
			(net "GND")
		)
	)
)
